(kicad_pcb
	(version 20260206)
	(generator "pcbnew")
	(generator_version "10.0")
	(general
		(thickness 1.6)
		(legacy_teardrops no)
	)
	(paper "A4")
	(title_block
		(title "12092022_DA0F0TMDCD0_F0T_Management_Board_D_brd_V3_OCP.brd")
		(comment 1 "Grand Teton / footprints 792-797 of 1440")
	)
	(layers
		(0 "F.Cu" signal "TOP")
		(4 "In1.Cu" signal "GND")
		(6 "In2.Cu" signal "IN1")
		(8 "In3.Cu" signal "GND1")
		(10 "In4.Cu" signal "IN2")
		(12 "In5.Cu" signal "VCC")
		(14 "In6.Cu" signal "VCC1")
		(16 "In7.Cu" signal "IN3")
		(18 "In8.Cu" signal "GND2")
		(20 "In9.Cu" signal "IN4")
		(22 "In10.Cu" signal "GND3")
		(2 "B.Cu" signal "BOTTOM")
		(9 "F.Adhes" user "F.Adhesive")
		(11 "B.Adhes" user "B.Adhesive")
		(13 "F.Paste" user "Package Geometry/Pastemask Top")
		(15 "B.Paste" user "Package Geometry/Pastemask Bottom")
		(5 "F.SilkS" user "Ref Des/Silkscreen Top")
		(7 "B.SilkS" user "Ref Des/Silkscreen Bottom")
		(1 "F.Mask" user "Board Geometry/Soldermask Top")
		(3 "B.Mask" user "Board Geometry/Soldermask Bottom")
		(17 "Dwgs.User" user "User.Drawings")
		(19 "Cmts.User" user "User.Comments")
		(21 "Eco1.User" user "User.Eco1")
		(23 "Eco2.User" user "User.Eco2")
		(25 "Edge.Cuts" user "Board Geometry/Outline")
		(27 "Margin" user)
		(31 "F.CrtYd" user "Package Geometry/Place Bound Top")
		(29 "B.CrtYd" user "Package Geometry/Place Bound Bottom")
		(35 "F.Fab" user "Ref Des/Assembly Top")
		(33 "B.Fab" user "Ref Des/Assembly Bottom")
	)
	(footprint ""
		(layer "B.Cu")
		(at 48.436022 -62.116462 90)
		(property "Reference" "R848"
			(at 0 0 90)
			(layer "B.SilkS")
			(hide yes)
			(effects
				(font
					(size 1.27 1.27)
				)
				(justify mirror)
			)
		)
		(property "Value" ""
			(at 0 0 90)
			(layer "B.Fab")
			(effects
				(font
					(size 1.27 1.27)
				)
				(justify mirror)
			)
		)
		(duplicate_pad_numbers_are_jumpers no)
		(fp_line
			(start 0.7874 -0.4064)
			(end -0.7874 -0.4064)
			(stroke
				(width 0.1524)
				(type default)
			)
			(layer "B.SilkS")
		)
		(fp_line
			(start -0.7874 -0.4064)
			(end -0.7874 0.4064)
			(stroke
				(width 0.1524)
				(type default)
			)
			(layer "B.SilkS")
		)
		(fp_line
			(start 0.7874 0.4064)
			(end 0.7874 -0.4064)
			(stroke
				(width 0.1524)
				(type default)
			)
			(layer "B.SilkS")
		)
		(fp_line
			(start -0.7874 0.4064)
			(end 0.7874 0.4064)
			(stroke
				(width 0.1524)
				(type default)
			)
			(layer "B.SilkS")
		)
		(fp_line
			(start 0.67945 -0.305054)
			(end 0.12065 -0.305054)
			(stroke
				(width 0.1)
				(type default)
			)
			(layer "B.Fab")
		)
		(fp_line
			(start 0.12065 -0.305054)
			(end 0.12065 -0.2794)
			(stroke
				(width 0.1)
				(type default)
			)
			(layer "B.Fab")
		)
		(fp_line
			(start -0.12065 -0.3048)
			(end -0.67945 -0.3048)
			(stroke
				(width 0.1)
				(type default)
			)
			(layer "B.Fab")
		)
		(fp_line
			(start -0.67945 -0.3048)
			(end -0.67945 0.3048)
			(stroke
				(width 0.1)
				(type default)
			)
			(layer "B.Fab")
		)
		(fp_line
			(start 0.12065 -0.2794)
			(end -0.12065 -0.2794)
			(stroke
				(width 0.1)
				(type default)
			)
			(layer "B.Fab")
		)
		(fp_line
			(start -0.12065 -0.2794)
			(end -0.12065 -0.3048)
			(stroke
				(width 0.1)
				(type default)
			)
			(layer "B.Fab")
		)
		(fp_line
			(start 0.12065 0.2794)
			(end 0.12065 0.3048)
			(stroke
				(width 0.1)
				(type default)
			)
			(layer "B.Fab")
		)
		(fp_line
			(start -0.120396 0.2794)
			(end 0.12065 0.2794)
			(stroke
				(width 0.1)
				(type default)
			)
			(layer "B.Fab")
		)
		(fp_line
			(start 0.67945 0.3048)
			(end 0.67945 -0.305054)
			(stroke
				(width 0.1)
				(type default)
			)
			(layer "B.Fab")
		)
		(fp_line
			(start 0.12065 0.3048)
			(end 0.67945 0.3048)
			(stroke
				(width 0.1)
				(type default)
			)
			(layer "B.Fab")
		)
		(fp_line
			(start -0.120396 0.3048)
			(end -0.120396 0.2794)
			(stroke
				(width 0.1)
				(type default)
			)
			(layer "B.Fab")
		)
		(fp_line
			(start -0.67945 0.3048)
			(end -0.120396 0.3048)
			(stroke
				(width 0.1)
				(type default)
			)
			(layer "B.Fab")
		)
		(pad "1" smd circle
			(at 0.40005 0 270)
			(size 0 0)
			(layers "B.Cu" "B.Mask" "B.Paste")
			(net "P3V3_AUX")
		)
		(pad "2" smd circle
			(at -0.40005 0 270)
			(size 0 0)
			(layers "B.Cu" "B.Mask" "B.Paste")
			(net "SMB_BMC_ALERT16_N")
		)
	)
	(footprint ""
		(layer "B.Cu")
		(at 85.29955 -42.395394 180)
		(property "Reference" "C14"
			(at 0 0 0)
			(layer "B.SilkS")
			(hide yes)
			(effects
				(font
					(size 1.27 1.27)
				)
				(justify mirror)
			)
		)
		(property "Value" ""
			(at 0 0 0)
			(layer "B.Fab")
			(effects
				(font
					(size 1.27 1.27)
				)
				(justify mirror)
			)
		)
		(duplicate_pad_numbers_are_jumpers no)
		(fp_line
			(start 0.7874 0.4064)
			(end 0.7874 -0.4064)
			(stroke
				(width 0.1524)
				(type default)
			)
			(layer "B.SilkS")
		)
		(fp_line
			(start 0.7874 -0.4064)
			(end -0.7874 -0.4064)
			(stroke
				(width 0.1524)
				(type default)
			)
			(layer "B.SilkS")
		)
		(fp_line
			(start -0.7874 0.4064)
			(end 0.7874 0.4064)
			(stroke
				(width 0.1524)
				(type default)
			)
			(layer "B.SilkS")
		)
		(fp_line
			(start -0.7874 -0.4064)
			(end -0.7874 0.4064)
			(stroke
				(width 0.1524)
				(type default)
			)
			(layer "B.SilkS")
		)
		(fp_line
			(start 0.67945 0.3048)
			(end 0.67945 -0.305054)
			(stroke
				(width 0.1)
				(type default)
			)
			(layer "B.Fab")
		)
		(fp_line
			(start 0.67945 -0.305054)
			(end 0.12065 -0.305054)
			(stroke
				(width 0.1)
				(type default)
			)
			(layer "B.Fab")
		)
		(fp_line
			(start 0.12065 0.3048)
			(end 0.67945 0.3048)
			(stroke
				(width 0.1)
				(type default)
			)
			(layer "B.Fab")
		)
		(fp_line
			(start 0.12065 0.2794)
			(end 0.12065 0.3048)
			(stroke
				(width 0.1)
				(type default)
			)
			(layer "B.Fab")
		)
		(fp_line
			(start 0.12065 -0.2794)
			(end -0.12065 -0.2794)
			(stroke
				(width 0.1)
				(type default)
			)
			(layer "B.Fab")
		)
		(fp_line
			(start 0.12065 -0.305054)
			(end 0.12065 -0.2794)
			(stroke
				(width 0.1)
				(type default)
			)
			(layer "B.Fab")
		)
		(fp_line
			(start -0.120396 0.3048)
			(end -0.120396 0.2794)
			(stroke
				(width 0.1)
				(type default)
			)
			(layer "B.Fab")
		)
		(fp_line
			(start -0.120396 0.2794)
			(end 0.12065 0.2794)
			(stroke
				(width 0.1)
				(type default)
			)
			(layer "B.Fab")
		)
		(fp_line
			(start -0.12065 -0.2794)
			(end -0.12065 -0.3048)
			(stroke
				(width 0.1)
				(type default)
			)
			(layer "B.Fab")
		)
		(fp_line
			(start -0.12065 -0.3048)
			(end -0.67945 -0.3048)
			(stroke
				(width 0.1)
				(type default)
			)
			(layer "B.Fab")
		)
		(fp_line
			(start -0.67945 0.3048)
			(end -0.120396 0.3048)
			(stroke
				(width 0.1)
				(type default)
			)
			(layer "B.Fab")
		)
		(fp_line
			(start -0.67945 -0.3048)
			(end -0.67945 0.3048)
			(stroke
				(width 0.1)
				(type default)
			)
			(layer "B.Fab")
		)
		(pad "1" smd circle
			(at 0.40005 0)
			(size 0 0)
			(layers "B.Cu" "B.Mask" "B.Paste")
			(net "P1V2_AUX")
		)
		(pad "2" smd circle
			(at -0.40005 0)
			(size 0 0)
			(layers "B.Cu" "B.Mask" "B.Paste")
			(net "GND")
		)
	)
	(footprint ""
		(layer "B.Cu")
		(at 24.3078 -24.003 -90)
		(property "Reference" "PC267"
			(at 0 0 90)
			(layer "B.SilkS")
			(hide yes)
			(effects
				(font
					(size 1.27 1.27)
				)
				(justify mirror)
			)
		)
		(property "Value" ""
			(at 0 0 90)
			(layer "B.Fab")
			(effects
				(font
					(size 1.27 1.27)
				)
				(justify mirror)
			)
		)
		(duplicate_pad_numbers_are_jumpers no)
		(fp_line
			(start -1.651 0.8382)
			(end 1.651 0.8382)
			(stroke
				(width 0.1524)
				(type default)
			)
			(layer "B.SilkS")
		)
		(fp_line
			(start 0 0.8382)
			(end 0 -0.8382)
			(stroke
				(width 0.1524)
				(type default)
			)
			(layer "B.SilkS")
		)
		(fp_line
			(start 1.651 0.8382)
			(end 1.651 -0.8382)
			(stroke
				(width 0.1524)
				(type default)
			)
			(layer "B.SilkS")
		)
		(fp_line
			(start -1.651 -0.8382)
			(end -1.651 0.8382)
			(stroke
				(width 0.1524)
				(type default)
			)
			(layer "B.SilkS")
		)
		(fp_line
			(start 1.651 -0.8382)
			(end -1.651 -0.8382)
			(stroke
				(width 0.1524)
				(type default)
			)
			(layer "B.SilkS")
		)
		(fp_line
			(start -1.55956 0.7366)
			(end -1.55956 -0.7366)
			(stroke
				(width 0.1)
				(type default)
			)
			(layer "B.Fab")
		)
		(fp_line
			(start -1.524 0.7366)
			(end -1.55956 0.7366)
			(stroke
				(width 0.1)
				(type default)
			)
			(layer "B.Fab")
		)
		(fp_line
			(start 1.524 0.7366)
			(end -1.524 0.7366)
			(stroke
				(width 0.1)
				(type default)
			)
			(layer "B.Fab")
		)
		(fp_line
			(start 1.55956 0.7366)
			(end 1.524 0.7366)
			(stroke
				(width 0.1)
				(type default)
			)
			(layer "B.Fab")
		)
		(fp_line
			(start -1.55956 -0.7366)
			(end -1.524 -0.7366)
			(stroke
				(width 0.1)
				(type default)
			)
			(layer "B.Fab")
		)
		(fp_line
			(start -1.524 -0.7366)
			(end 1.524 -0.7366)
			(stroke
				(width 0.1)
				(type default)
			)
			(layer "B.Fab")
		)
		(fp_line
			(start 1.524 -0.7366)
			(end 1.55956 -0.7366)
			(stroke
				(width 0.1)
				(type default)
			)
			(layer "B.Fab")
		)
		(fp_line
			(start 1.55956 -0.7366)
			(end 1.55956 0.7366)
			(stroke
				(width 0.1)
				(type default)
			)
			(layer "B.Fab")
		)
		(pad "1" smd rect
			(at 0.94996 0 270)
			(size 1.1176 1.3716)
			(layers "B.Cu" "B.Mask" "B.Paste")
			(net "P1V0_AUX")
		)
		(pad "2" smd rect
			(at -0.94996 0 270)
			(size 1.1176 1.3716)
			(layers "B.Cu" "B.Mask" "B.Paste")
			(net "GND")
		)
	)
	(footprint ""
		(layer "B.Cu")
		(at 56.43626 -47.606966 90)
		(property "Reference" "C99"
			(at 0 0 90)
			(layer "B.SilkS")
			(hide yes)
			(effects
				(font
					(size 1.27 1.27)
				)
				(justify mirror)
			)
		)
		(property "Value" ""
			(at 0 0 90)
			(layer "B.Fab")
			(effects
				(font
					(size 1.27 1.27)
				)
				(justify mirror)
			)
		)
		(duplicate_pad_numbers_are_jumpers no)
		(fp_line
			(start 0.7874 -0.4064)
			(end -0.7874 -0.4064)
			(stroke
				(width 0.1524)
				(type default)
			)
			(layer "B.SilkS")
		)
		(fp_line
			(start -0.7874 -0.4064)
			(end -0.7874 0.4064)
			(stroke
				(width 0.1524)
				(type default)
			)
			(layer "B.SilkS")
		)
		(fp_line
			(start 0.7874 0.4064)
			(end 0.7874 -0.4064)
			(stroke
				(width 0.1524)
				(type default)
			)
			(layer "B.SilkS")
		)
		(fp_line
			(start -0.7874 0.4064)
			(end 0.7874 0.4064)
			(stroke
				(width 0.1524)
				(type default)
			)
			(layer "B.SilkS")
		)
		(fp_line
			(start 0.67945 -0.305054)
			(end 0.12065 -0.305054)
			(stroke
				(width 0.1)
				(type default)
			)
			(layer "B.Fab")
		)
		(fp_line
			(start 0.12065 -0.305054)
			(end 0.12065 -0.2794)
			(stroke
				(width 0.1)
				(type default)
			)
			(layer "B.Fab")
		)
		(fp_line
			(start -0.12065 -0.3048)
			(end -0.67945 -0.3048)
			(stroke
				(width 0.1)
				(type default)
			)
			(layer "B.Fab")
		)
		(fp_line
			(start -0.67945 -0.3048)
			(end -0.67945 0.3048)
			(stroke
				(width 0.1)
				(type default)
			)
			(layer "B.Fab")
		)
		(fp_line
			(start 0.12065 -0.2794)
			(end -0.12065 -0.2794)
			(stroke
				(width 0.1)
				(type default)
			)
			(layer "B.Fab")
		)
		(fp_line
			(start -0.12065 -0.2794)
			(end -0.12065 -0.3048)
			(stroke
				(width 0.1)
				(type default)
			)
			(layer "B.Fab")
		)
		(fp_line
			(start 0.12065 0.2794)
			(end 0.12065 0.3048)
			(stroke
				(width 0.1)
				(type default)
			)
			(layer "B.Fab")
		)
		(fp_line
			(start -0.120396 0.2794)
			(end 0.12065 0.2794)
			(stroke
				(width 0.1)
				(type default)
			)
			(layer "B.Fab")
		)
		(fp_line
			(start 0.67945 0.3048)
			(end 0.67945 -0.305054)
			(stroke
				(width 0.1)
				(type default)
			)
			(layer "B.Fab")
		)
		(fp_line
			(start 0.12065 0.3048)
			(end 0.67945 0.3048)
			(stroke
				(width 0.1)
				(type default)
			)
			(layer "B.Fab")
		)
		(fp_line
			(start -0.120396 0.3048)
			(end -0.120396 0.2794)
			(stroke
				(width 0.1)
				(type default)
			)
			(layer "B.Fab")
		)
		(fp_line
			(start -0.67945 0.3048)
			(end -0.120396 0.3048)
			(stroke
				(width 0.1)
				(type default)
			)
			(layer "B.Fab")
		)
		(pad "1" smd circle
			(at 0.40005 0 270)
			(size 0 0)
			(layers "B.Cu" "B.Mask" "B.Paste")
			(net "P1V0_AUX")
		)
		(pad "2" smd circle
			(at -0.40005 0 270)
			(size 0 0)
			(layers "B.Cu" "B.Mask" "B.Paste")
			(net "GND")
		)
	)
	(footprint ""
		(layer "B.Cu")
		(at 50.155602 -43.303952 -90)
		(property "Reference" "C57"
			(at 0 0 90)
			(layer "B.SilkS")
			(hide yes)
			(effects
				(font
					(size 1.27 1.27)
				)
				(justify mirror)
			)
		)
		(property "Value" ""
			(at 0 0 90)
			(layer "B.Fab")
			(effects
				(font
					(size 1.27 1.27)
				)
				(justify mirror)
			)
		)
		(duplicate_pad_numbers_are_jumpers no)
		(fp_line
			(start -0.7874 0.4064)
			(end 0.7874 0.4064)
			(stroke
				(width 0.1524)
				(type default)
			)
			(layer "B.SilkS")
		)
		(fp_line
			(start 0.7874 0.4064)
			(end 0.7874 -0.4064)
			(stroke
				(width 0.1524)
				(type default)
			)
			(layer "B.SilkS")
		)
		(fp_line
			(start -0.7874 -0.4064)
			(end -0.7874 0.4064)
			(stroke
				(width 0.1524)
				(type default)
			)
			(layer "B.SilkS")
		)
		(fp_line
			(start 0.7874 -0.4064)
			(end -0.7874 -0.4064)
			(stroke
				(width 0.1524)
				(type default)
			)
			(layer "B.SilkS")
		)
		(fp_line
			(start -0.67945 0.3048)
			(end -0.120396 0.3048)
			(stroke
				(width 0.1)
				(type default)
			)
			(layer "B.Fab")
		)
		(fp_line
			(start -0.120396 0.3048)
			(end -0.120396 0.2794)
			(stroke
				(width 0.1)
				(type default)
			)
			(layer "B.Fab")
		)
		(fp_line
			(start 0.12065 0.3048)
			(end 0.67945 0.3048)
			(stroke
				(width 0.1)
				(type default)
			)
			(layer "B.Fab")
		)
		(fp_line
			(start 0.67945 0.3048)
			(end 0.67945 -0.305054)
			(stroke
				(width 0.1)
				(type default)
			)
			(layer "B.Fab")
		)
		(fp_line
			(start -0.120396 0.2794)
			(end 0.12065 0.2794)
			(stroke
				(width 0.1)
				(type default)
			)
			(layer "B.Fab")
		)
		(fp_line
			(start 0.12065 0.2794)
			(end 0.12065 0.3048)
			(stroke
				(width 0.1)
				(type default)
			)
			(layer "B.Fab")
		)
		(fp_line
			(start -0.12065 -0.2794)
			(end -0.12065 -0.3048)
			(stroke
				(width 0.1)
				(type default)
			)
			(layer "B.Fab")
		)
		(fp_line
			(start 0.12065 -0.2794)
			(end -0.12065 -0.2794)
			(stroke
				(width 0.1)
				(type default)
			)
			(layer "B.Fab")
		)
		(fp_line
			(start -0.67945 -0.3048)
			(end -0.67945 0.3048)
			(stroke
				(width 0.1)
				(type default)
			)
			(layer "B.Fab")
		)
		(fp_line
			(start -0.12065 -0.3048)
			(end -0.67945 -0.3048)
			(stroke
				(width 0.1)
				(type default)
			)
			(layer "B.Fab")
		)
		(fp_line
			(start 0.12065 -0.305054)
			(end 0.12065 -0.2794)
			(stroke
				(width 0.1)
				(type default)
			)
			(layer "B.Fab")
		)
		(fp_line
			(start 0.67945 -0.305054)
			(end 0.12065 -0.305054)
			(stroke
				(width 0.1)
				(type default)
			)
			(layer "B.Fab")
		)
		(pad "1" smd circle
			(at 0.40005 0 90)
			(size 0 0)
			(layers "B.Cu" "B.Mask" "B.Paste")
			(net "P3V3_P1V8_I2C_I3C")
		)
		(pad "2" smd circle
			(at -0.40005 0 90)
			(size 0 0)
			(layers "B.Cu" "B.Mask" "B.Paste")
			(net "GND")
		)
	)
	(footprint ""
		(layer "B.Cu")
		(at 17.78 -70.104 90)
		(property "Reference" "R298"
			(at 0 0 90)
			(layer "B.SilkS")
			(hide yes)
			(effects
				(font
					(size 1.27 1.27)
				)
				(justify mirror)
			)
		)
		(property "Value" ""
			(at 0 0 90)
			(layer "B.Fab")
			(effects
				(font
					(size 1.27 1.27)
				)
				(justify mirror)
			)
		)
		(duplicate_pad_numbers_are_jumpers no)
		(fp_line
			(start 0.7874 -0.4064)
			(end -0.7874 -0.4064)
			(stroke
				(width 0.1524)
				(type default)
			)
			(layer "B.SilkS")
		)
		(fp_line
			(start -0.7874 -0.4064)
			(end -0.7874 0.4064)
			(stroke
				(width 0.1524)
				(type default)
			)
			(layer "B.SilkS")
		)
		(fp_line
			(start 0.7874 0.4064)
			(end 0.7874 -0.4064)
			(stroke
				(width 0.1524)
				(type default)
			)
			(layer "B.SilkS")
		)
		(fp_line
			(start -0.7874 0.4064)
			(end 0.7874 0.4064)
			(stroke
				(width 0.1524)
				(type default)
			)
			(layer "B.SilkS")
		)
		(fp_line
			(start 0.67945 -0.305054)
			(end 0.12065 -0.305054)
			(stroke
				(width 0.1)
				(type default)
			)
			(layer "B.Fab")
		)
		(fp_line
			(start 0.12065 -0.305054)
			(end 0.12065 -0.2794)
			(stroke
				(width 0.1)
				(type default)
			)
			(layer "B.Fab")
		)
		(fp_line
			(start -0.12065 -0.3048)
			(end -0.67945 -0.3048)
			(stroke
				(width 0.1)
				(type default)
			)
			(layer "B.Fab")
		)
		(fp_line
			(start -0.67945 -0.3048)
			(end -0.67945 0.3048)
			(stroke
				(width 0.1)
				(type default)
			)
			(layer "B.Fab")
		)
		(fp_line
			(start 0.12065 -0.2794)
			(end -0.12065 -0.2794)
			(stroke
				(width 0.1)
				(type default)
			)
			(layer "B.Fab")
		)
		(fp_line
			(start -0.12065 -0.2794)
			(end -0.12065 -0.3048)
			(stroke
				(width 0.1)
				(type default)
			)
			(layer "B.Fab")
		)
		(fp_line
			(start 0.12065 0.2794)
			(end 0.12065 0.3048)
			(stroke
				(width 0.1)
				(type default)
			)
			(layer "B.Fab")
		)
		(fp_line
			(start -0.120396 0.2794)
			(end 0.12065 0.2794)
			(stroke
				(width 0.1)
				(type default)
			)
			(layer "B.Fab")
		)
		(fp_line
			(start 0.67945 0.3048)
			(end 0.67945 -0.305054)
			(stroke
				(width 0.1)
				(type default)
			)
			(layer "B.Fab")
		)
		(fp_line
			(start 0.12065 0.3048)
			(end 0.67945 0.3048)
			(stroke
				(width 0.1)
				(type default)
			)
			(layer "B.Fab")
		)
		(fp_line
			(start -0.120396 0.3048)
			(end -0.120396 0.2794)
			(stroke
				(width 0.1)
				(type default)
			)
			(layer "B.Fab")
		)
		(fp_line
			(start -0.67945 0.3048)
			(end -0.120396 0.3048)
			(stroke
				(width 0.1)
				(type default)
			)
			(layer "B.Fab")
		)
		(pad "1" smd circle
			(at 0.40005 0 270)
			(size 0 0)
			(layers "B.Cu" "B.Mask" "B.Paste")
			(net "P3V3_AUX")
		)
		(pad "2" smd circle
			(at -0.40005 0 270)
			(size 0 0)
			(layers "B.Cu" "B.Mask" "B.Paste")
			(net "SMB_DEBUG_AUX_LVC3_USB_R1_SCL")
		)
	)
)
